#ISCELL
  logical_power cad_note *
  *
#ISCELL
  mstr_misc dns *
  *
#ISCELL
  pure_quanta quanta_title_block_c *
  *
#ISCELL
  logical_power universal_power *
  page249_i1
#ISCELL
  logical_power universal_gnd *
  page249_i10
#CELL
  pure_quanta q_res *
  page249_i11
#ISCELL
  standard offpage *
  page249_i12
#ISCELL
  logical_power gnd *
  page249_i13
#CELL
  pure_quanta q_cap *
  page249_i14
#ISCELL
  logical_power vccaux15 *
  page249_i15
#CELL
  pure_quanta q_inductor *
  page249_i16
#CELL
  pure_quanta q_res *
  page249_i17
#ISCELL
  logical_power universal_gnd *
  page249_i18
#CELL
  pure_quanta q_cap *
  page249_i19
#CELL
  pure_quanta q_res *
  page249_i2
#CELL
  pure_quanta q_cap *
  page249_i20
#CELL
  pure_quanta q_cap *
  page249_i21
#ISCELL
  logical_power universal_power *
  page249_i22
#ISCELL
  logical_power universal_power *
  page249_i23
#CELL
  pure_quanta q_res *
  page249_i24
#ISCELL
  logical_power universal_gnd *
  page249_i25
#CELL
  pure_quanta nb682gdz *
  page249_i26
#ISCELL
  logical_power universal_gnd *
  page249_i27
#CELL
  pure_quanta q_cap *
  page249_i28
#CELL
  pure_quanta q_cap *
  page249_i29
#ISCELL
  logical_power universal_gnd *
  page249_i3
#CELL
  pure_quanta q_cap *
  page249_i30
#CELL
  pure_quanta q_res *
  page249_i31
#ISCELL
  logical_power universal_power *
  page249_i32
#CELL
  pure_quanta q_res *
  page249_i34
#ISCELL
  logical_power universal_gnd *
  page249_i35
#CELL
  pure_quanta q_cap *
  page249_i36
#CELL
  pure_quanta q_cap *
  page249_i37
#CELL
  pure_quanta q_cap *
  page249_i38
#CELL
  pure_quanta q_cap *
  page249_i39
#CELL
  pure_quanta q_cap *
  page249_i4
#ISCELL
  logical_power universal_gnd *
  page249_i40
#CELL
  pure_quanta q_cap *
  page249_i41
#CELL
  pure_quanta q_res *
  page249_i42
#ISCELL
  standard offpage *
  page249_i43
#ISCELL
  logical_power universal_power *
  page249_i44
#CELL
  pure_quanta q_inductor *
  page249_i45
#CELL
  pure_quanta q_res *
  page249_i5
#ISCELL
  logical_power universal_power *
  page249_i6
#ISCELL
  logical_power universal_power *
  page249_i7
#CELL
  pure_quanta q_res *
  page249_i8
#ISCELL
  logical_power universal_gnd *
  page249_i9
